(kicad_pcb
	(version 20241229)
	(generator "pcbnew")
	(generator_version "9.0")
	(general
		(thickness 1.6)
		(legacy_teardrops no)
	)
	(paper "A4")
	(title_block
		(title "GMSL Deserializer")
		(date "2025-10-09")
		(rev "1.0.4")
		(company "Antmicro Ltd")
		(comment 1 "www.antmicro.com")
		(comment 9 "footprints 196-199 of 235")
	)
	(layers
		(0 "F.Cu" signal)
		(4 "In1.Cu" power)
		(6 "In2.Cu" power)
		(2 "B.Cu" signal)
		(9 "F.Adhes" user "F.Adhesive")
		(11 "B.Adhes" user "B.Adhesive")
		(13 "F.Paste" user)
		(15 "B.Paste" user)
		(5 "F.SilkS" user "F.Silkscreen")
		(7 "B.SilkS" user "B.Silkscreen")
		(1 "F.Mask" user)
		(3 "B.Mask" user)
		(17 "Dwgs.User" user "User.Drawings")
		(19 "Cmts.User" user "User.Comments")
		(21 "Eco1.User" user "User.Eco1")
		(23 "Eco2.User" user "User.Eco2")
		(25 "Edge.Cuts" user)
		(27 "Margin" user)
		(31 "F.CrtYd" user "F.Courtyard")
		(29 "B.CrtYd" user "B.Courtyard")
		(35 "F.Fab" user)
		(33 "B.Fab" user)
	)
	(footprint "antmicro-footprints:C_0402_1005Metric"
		(layer "B.Cu")
		(at 141.986 77.978 -45)
		(descr "Capacitor SMD 0402")
		(tags "capacitor SMD 0402")
		(property "Reference" "C42"
			(at -1.52271 0.22729 315)
			(unlocked yes)
			(layer "B.SilkS")
			(effects
				(font
					(size 0.7 0.7)
					(thickness 0.15)
				)
				(justify left bottom mirror)
			)
		)
		(property "Value" "C_10n_0402"
			(at -1.022927 -2.155213 135)
			(layer "B.Fab")
			(effects
				(font
					(size 0.7 0.7)
					(thickness 0.15)
				)
				(justify left bottom mirror)
			)
		)
		(property "Datasheet" "https://www.murata.com/products/productdetail?partno=GRM155R71H103KA88%23"
			(at 0 0 315)
			(layer "F.Fab")
			(hide yes)
			(effects
				(font
					(size 1.27 1.27)
					(thickness 0.15)
				)
			)
		)
		(property "Description" "SMD Multilayer Ceramic Capacitor, 10000 pF, 50 V, 0402 [1005 Metric], ± 10%, X7R, GRM Series"
			(at 0 0 315)
			(layer "F.Fab")
			(hide yes)
			(effects
				(font
					(size 1.27 1.27)
					(thickness 0.15)
				)
			)
		)
		(property "Author" "Antmicro"
			(at -13.552036 123.238491 0)
			(layer "B.Fab")
			(hide yes)
			(effects
				(font
					(size 1 1)
					(thickness 0.15)
				)
				(justify mirror)
			)
		)
		(property "Dielectric" "X7R"
			(at -13.552036 123.238491 0)
			(layer "B.Fab")
			(hide yes)
			(effects
				(font
					(size 1 1)
					(thickness 0.15)
				)
				(justify mirror)
			)
		)
		(property "License" "Apache-2.0"
			(at -13.552036 123.238491 0)
			(layer "B.Fab")
			(hide yes)
			(effects
				(font
					(size 1 1)
					(thickness 0.15)
				)
				(justify mirror)
			)
		)
		(property "MPN" "GRM155R71H103KA88D"
			(at -13.552036 123.238491 0)
			(layer "B.Fab")
			(hide yes)
			(effects
				(font
					(size 1 1)
					(thickness 0.15)
				)
				(justify mirror)
			)
		)
		(property "Manufacturer" "Murata"
			(at -13.552036 123.238491 0)
			(layer "B.Fab")
			(hide yes)
			(effects
				(font
					(size 1 1)
					(thickness 0.15)
				)
				(justify mirror)
			)
		)
		(property "Val" "10n"
			(at -13.552036 123.238491 0)
			(layer "B.Fab")
			(hide yes)
			(effects
				(font
					(size 1 1)
					(thickness 0.15)
				)
				(justify mirror)
			)
		)
		(property "Voltage" "50V"
			(at -13.552036 123.238491 0)
			(layer "B.Fab")
			(hide yes)
			(effects
				(font
					(size 1 1)
					(thickness 0.15)
				)
				(justify mirror)
			)
		)
		(sheetname "/Deserializer/")
		(sheetfile "deserializer.kicad_sch")
		(attr smd)
		(fp_poly
			(pts
				(xy -0.925 0.47) (xy 0.925 0.47) (xy 0.925 -0.47) (xy -0.925 -0.47)
			)
			(stroke
				(width 0.05)
				(type default)
			)
			(fill no)
			(layer "B.CrtYd")
		)
		(fp_line
			(start -0.494 0.25)
			(end -0.494 -0.248)
			(stroke
				(width 0.15)
				(type solid)
			)
			(layer "B.Fab")
		)
		(fp_line
			(start -0.494 -0.248)
			(end 0.504 -0.248)
			(stroke
				(width 0.15)
				(type solid)
			)
			(layer "B.Fab")
		)
		(fp_line
			(start 0.504 0.25)
			(end -0.494 0.25)
			(stroke
				(width 0.15)
				(type solid)
			)
			(layer "B.Fab")
		)
		(fp_line
			(start 0.504 -0.248)
			(end 0.504 0.25)
			(stroke
				(width 0.15)
				(type solid)
			)
			(layer "B.Fab")
		)
		(pad "1" smd roundrect
			(at -0.48 0 315)
			(size 0.59 0.64)
			(layers "B.Cu" "B.Mask" "B.Paste")
			(roundrect_rratio 0.25)
			(net 1 "GND")
			(pintype "passive")
		)
		(pad "2" smd roundrect
			(at 0.48 0 315)
			(size 0.59 0.64)
			(layers "B.Cu" "B.Mask" "B.Paste")
			(roundrect_rratio 0.25)
			(net 26 "/Deserializer/VDD_1.8V")
			(pintype "passive")
		)
	)
	(footprint "antmicro-footprints:Spacer_Drill3.7mm_H6mm_9774060151R"
		(layer "B.Cu")
		(at 184.372 46.068 180)
		(descr "Spacer M=3 h=36mm fi=5.1mm")
		(property "Reference" "H2"
			(at 0 3.2 0)
			(layer "B.SilkS")
			(effects
				(font
					(size 0.7 0.7)
					(thickness 0.15)
				)
				(justify left bottom mirror)
			)
		)
		(property "Value" "Spacer_Drill3.7mm_H6mm_9774060151R"
			(at 0 -4 0)
			(layer "B.Fab")
			(effects
				(font
					(size 0.7 0.7)
					(thickness 0.15)
				)
				(justify left bottom mirror)
			)
		)
		(property "Datasheet" "https://www.we-online.com/components/products/datasheet/9774060151R.pdf"
			(at 0 0 180)
			(layer "F.Fab")
			(hide yes)
			(effects
				(font
					(size 1.27 1.27)
					(thickness 0.15)
				)
			)
		)
		(property "Description" "Spacer, SMT, Non Stop, Steel, Swage Round, 5.1 mm x 6 mm, M2.5 Thread, WA-SMSI Series"
			(at 0 0 180)
			(layer "F.Fab")
			(hide yes)
			(effects
				(font
					(size 1.27 1.27)
					(thickness 0.15)
				)
			)
		)
		(property "Author" "Antmicro"
			(at 368.744 92.136 0)
			(layer "B.Fab")
			(hide yes)
			(effects
				(font
					(size 1 1)
					(thickness 0.15)
				)
				(justify mirror)
			)
		)
		(property "License" "Apache-2.0"
			(at 368.744 92.136 0)
			(layer "B.Fab")
			(hide yes)
			(effects
				(font
					(size 1 1)
					(thickness 0.15)
				)
				(justify mirror)
			)
		)
		(property "MPN" "9774060151R"
			(at 368.744 92.136 0)
			(layer "B.Fab")
			(hide yes)
			(effects
				(font
					(size 1 1)
					(thickness 0.15)
				)
				(justify mirror)
			)
		)
		(property "Manufacturer" "Würth Elektronik"
			(at 368.744 92.136 0)
			(layer "B.Fab")
			(hide yes)
			(effects
				(font
					(size 1 1)
					(thickness 0.15)
				)
				(justify mirror)
			)
		)
		(sheetname "/")
		(sheetfile "gmsl-deserializer.kicad_sch")
		(solder_paste_margin_ratio -1)
		(attr smd)
		(fp_circle
			(center 0 0)
			(end 3.05 0)
			(stroke
				(width 0.05)
				(type solid)
			)
			(fill no)
			(layer "B.CrtYd")
		)
		(fp_circle
			(center 0 0)
			(end 2.6 0)
			(stroke
				(width 0.15)
				(type solid)
			)
			(fill no)
			(layer "B.Fab")
		)
		(pad "" smd custom
			(at -1.7 -1.7 90)
			(size 0.62 0.62)
			(layers "B.Paste")
			(thermal_bridge_angle 90)
			(options
				(clearance outline)
				(anchor circle)
			)
			(primitives
				(gr_arc
					(start 1.266786 0.24747)
					(mid 0.285453 -0.29439)
					(end -0.250195 -1.279127)
					(width 0.2)
				)
				(gr_arc
					(start 1.259603 0.339191)
					(mid 0.218448 -0.232561)
					(end -0.34334 -1.279127)
					(width 0.2)
				)
				(gr_arc
					(start 1.255279 0.431435)
					(mid 0.152481 -0.169693)
					(end -0.436309 -1.279127)
					(width 0.2)
				)
				(gr_arc
					(start 1.253811 0.524161)
					(mid 0.087542 -0.105784)
					(end -0.529126 -1.279127)
					(width 0.2)
				)
				(gr_arc
					(start 1.275473 0.621136)
					(mid 0.0309 -0.033527)
					(end -0.621807 -1.279127)
					(width 0.2)
				)
				(gr_arc
					(start 1.263664 0.711602)
					(mid -0.037759 0.026651)
					(end -0.71437 -1.279127)
					(width 0.2)
				)
				(gr_arc
					(start 1.253435 0.802342)
					(mid -0.105837 0.087395)
					(end -0.806826 -1.279127)
					(width 0.2)
				)
				(gr_arc
					(start 1.267475 0.897258)
					(mid -0.165236 0.156885)
					(end -0.899187 -1.279127)
					(width 0.2)
				)
				(gr_arc
					(start 1.270645 0.990112)
					(mid -0.228522 0.222449)
					(end -0.991463 -1.279127)
					(width 0.2)
				)
				(gr_arc
					(start 1.266278 1.081674)
					(mid -0.294507 0.285313)
					(end -1.083663 -1.279127)
					(width 0.2)
				)
				(gr_line
					(start 1.279127 0.250195)
					(end 1.279127 1.083663)
					(width 0.2)
				)
				(gr_line
					(start -0.250195 -1.279127)
					(end -1.083663 -1.279127)
					(width 0.2)
				)
			)
		)
		(pad "" smd custom
			(at -1.7 1.7 180)
			(size 0.62 0.62)
			(layers "B.Paste")
			(thermal_bridge_angle 90)
			(options
				(clearance outline)
				(anchor circle)
			)
			(primitives
				(gr_arc
					(start 1.266786 0.24747)
					(mid 0.285453 -0.29439)
					(end -0.250195 -1.279127)
					(width 0.2)
				)
				(gr_arc
					(start 1.259603 0.339191)
					(mid 0.218448 -0.232561)
					(end -0.34334 -1.279127)
					(width 0.2)
				)
				(gr_arc
					(start 1.255279 0.431435)
					(mid 0.152481 -0.169693)
					(end -0.436309 -1.279127)
					(width 0.2)
				)
				(gr_arc
					(start 1.253811 0.524161)
					(mid 0.087542 -0.105784)
					(end -0.529126 -1.279127)
					(width 0.2)
				)
				(gr_arc
					(start 1.275473 0.621136)
					(mid 0.0309 -0.033527)
					(end -0.621807 -1.279127)
					(width 0.2)
				)
				(gr_arc
					(start 1.263664 0.711602)
					(mid -0.037759 0.026651)
					(end -0.71437 -1.279127)
					(width 0.2)
				)
				(gr_arc
					(start 1.253435 0.802342)
					(mid -0.105837 0.087395)
					(end -0.806826 -1.279127)
					(width 0.2)
				)
				(gr_arc
					(start 1.267475 0.897258)
					(mid -0.165236 0.156885)
					(end -0.899187 -1.279127)
					(width 0.2)
				)
				(gr_arc
					(start 1.270645 0.990112)
					(mid -0.228522 0.222449)
					(end -0.991463 -1.279127)
					(width 0.2)
				)
				(gr_arc
					(start 1.266278 1.081674)
					(mid -0.294507 0.285313)
					(end -1.083663 -1.279127)
					(width 0.2)
				)
				(gr_line
					(start 1.279127 0.250195)
					(end 1.279127 1.083663)
					(width 0.2)
				)
				(gr_line
					(start -0.250195 -1.279127)
					(end -1.083663 -1.279127)
					(width 0.2)
				)
			)
		)
		(pad "" smd custom
			(at 1.7 -1.7)
			(size 0.62 0.62)
			(layers "B.Paste")
			(thermal_bridge_angle 90)
			(options
				(clearance outline)
				(anchor circle)
			)
			(primitives
				(gr_arc
					(start 1.266786 0.24747)
					(mid 0.285453 -0.29439)
					(end -0.250195 -1.279127)
					(width 0.2)
				)
				(gr_arc
					(start 1.259603 0.339191)
					(mid 0.218448 -0.232561)
					(end -0.34334 -1.279127)
					(width 0.2)
				)
				(gr_arc
					(start 1.255279 0.431435)
					(mid 0.152481 -0.169693)
					(end -0.436309 -1.279127)
					(width 0.2)
				)
				(gr_arc
					(start 1.253811 0.524161)
					(mid 0.087542 -0.105784)
					(end -0.529126 -1.279127)
					(width 0.2)
				)
				(gr_arc
					(start 1.275473 0.621136)
					(mid 0.0309 -0.033527)
					(end -0.621807 -1.279127)
					(width 0.2)
				)
				(gr_arc
					(start 1.263664 0.711602)
					(mid -0.037759 0.026651)
					(end -0.71437 -1.279127)
					(width 0.2)
				)
				(gr_arc
					(start 1.253435 0.802342)
					(mid -0.105837 0.087395)
					(end -0.806826 -1.279127)
					(width 0.2)
				)
				(gr_arc
					(start 1.267475 0.897258)
					(mid -0.165236 0.156885)
					(end -0.899187 -1.279127)
					(width 0.2)
				)
				(gr_arc
					(start 1.270645 0.990112)
					(mid -0.228522 0.222449)
					(end -0.991463 -1.279127)
					(width 0.2)
				)
				(gr_arc
					(start 1.266278 1.081674)
					(mid -0.294507 0.285313)
					(end -1.083663 -1.279127)
					(width 0.2)
				)
				(gr_line
					(start 1.279127 0.250195)
					(end 1.279127 1.083663)
					(width 0.2)
				)
				(gr_line
					(start -0.250195 -1.279127)
					(end -1.083663 -1.279127)
					(width 0.2)
				)
			)
		)
		(pad "" smd custom
			(at 1.7 1.7 270)
			(size 0.62 0.62)
			(layers "B.Paste")
			(thermal_bridge_angle 90)
			(options
				(clearance outline)
				(anchor circle)
			)
			(primitives
				(gr_arc
					(start 1.266786 0.24747)
					(mid 0.285453 -0.29439)
					(end -0.250195 -1.279127)
					(width 0.2)
				)
				(gr_arc
					(start 1.259603 0.339191)
					(mid 0.218448 -0.232561)
					(end -0.34334 -1.279127)
					(width 0.2)
				)
				(gr_arc
					(start 1.255279 0.431435)
					(mid 0.152481 -0.169693)
					(end -0.436309 -1.279127)
					(width 0.2)
				)
				(gr_arc
					(start 1.253811 0.524161)
					(mid 0.087542 -0.105784)
					(end -0.529126 -1.279127)
					(width 0.2)
				)
				(gr_arc
					(start 1.275473 0.621136)
					(mid 0.0309 -0.033527)
					(end -0.621807 -1.279127)
					(width 0.2)
				)
				(gr_arc
					(start 1.263664 0.711602)
					(mid -0.037759 0.026651)
					(end -0.71437 -1.279127)
					(width 0.2)
				)
				(gr_arc
					(start 1.253435 0.802342)
					(mid -0.105837 0.087395)
					(end -0.806826 -1.279127)
					(width 0.2)
				)
				(gr_arc
					(start 1.267475 0.897258)
					(mid -0.165236 0.156885)
					(end -0.899187 -1.279127)
					(width 0.2)
				)
				(gr_arc
					(start 1.270645 0.990112)
					(mid -0.228522 0.222449)
					(end -0.991463 -1.279127)
					(width 0.2)
				)
				(gr_arc
					(start 1.266278 1.081674)
					(mid -0.294507 0.285313)
					(end -1.083663 -1.279127)
					(width 0.2)
				)
				(gr_line
					(start 1.279127 0.250195)
					(end 1.279127 1.083663)
					(width 0.2)
				)
				(gr_line
					(start -0.250195 -1.279127)
					(end -1.083663 -1.279127)
					(width 0.2)
				)
			)
		)
		(pad "1" thru_hole circle
			(at 0 0 180)
			(size 6 6)
			(drill 3.7)
			(layers "*.Cu" "*.Mask")
			(remove_unused_layers no)
			(net 1 "GND")
			(pintype "passive")
		)
	)
	(footprint "antmicro-footprints:TP_SMD_0.75mm"
		(layer "B.Cu")
		(at 153.924 97.89 180)
		(property "Reference" "TP21"
			(at 0 0.6 0)
			(layer "B.SilkS")
			(hide yes)
			(effects
				(font
					(size 0.7 0.7)
					(thickness 0.15)
				)
				(justify left bottom mirror)
			)
		)
		(property "Value" "TP_0.75mm_SMD"
			(at 0 -1.2 0)
			(layer "B.Fab")
			(effects
				(font
					(size 0.7 0.7)
					(thickness 0.15)
				)
				(justify left bottom mirror)
			)
		)
		(property "Description" "SMT test point"
			(at 0 0 0)
			(layer "B.Fab")
			(hide yes)
			(effects
				(font
					(size 1.27 1.27)
					(thickness 0.15)
				)
				(justify mirror)
			)
		)
		(property "MPN" ""
			(at 0 0 0)
			(unlocked yes)
			(layer "B.Fab")
			(hide yes)
			(effects
				(font
					(size 1 1)
					(thickness 0.15)
				)
				(justify mirror)
			)
		)
		(property "Manufacturer" ""
			(at 0 0 0)
			(unlocked yes)
			(layer "B.Fab")
			(hide yes)
			(effects
				(font
					(size 1 1)
					(thickness 0.15)
				)
				(justify mirror)
			)
		)
		(property "Author" "Antmicro"
			(at 0 0 0)
			(unlocked yes)
			(layer "B.Fab")
			(hide yes)
			(effects
				(font
					(size 1 1)
					(thickness 0.15)
				)
				(justify mirror)
			)
		)
		(property "License" "Apache-2.0"
			(at 0 0 0)
			(unlocked yes)
			(layer "B.Fab")
			(hide yes)
			(effects
				(font
					(size 1 1)
					(thickness 0.15)
				)
				(justify mirror)
			)
		)
		(sheetname "/Power/")
		(sheetfile "power.kicad_sch")
		(attr exclude_from_pos_files)
		(fp_circle
			(center 0 0)
			(end 0.475 0)
			(stroke
				(width 0.05)
				(type default)
			)
			(fill no)
			(layer "B.CrtYd")
		)
		(fp_text user "${REFERENCE}"
			(at -0.4 -2.7 0)
			(layer "B.Fab")
			(effects
				(font
					(size 0.7 0.7)
					(thickness 0.15)
				)
				(justify left bottom mirror)
			)
		)
		(fp_text user "License: Apache-2.0"
			(at -0.4 -5.101 0)
			(layer "B.Fab")
			(effects
				(font
					(size 0.7 0.7)
					(thickness 0.15)
				)
				(justify left bottom mirror)
			)
		)
		(fp_text user "Author: Antmicro"
			(at -0.4 -3.901 0)
			(layer "B.Fab")
			(effects
				(font
					(size 0.7 0.7)
					(thickness 0.15)
				)
				(justify left bottom mirror)
			)
		)
		(pad "1" smd circle
			(at 0 0 180)
			(size 0.75 0.75)
			(layers "B.Cu" "B.Mask")
			(net 118 "/Connectors/DC_IN")
			(pinfunction "1")
			(pintype "passive")
		)
	)
	(footprint "antmicro-footprints:C_0402_1005Metric"
		(layer "B.Cu")
		(at 150.622 77.724 -135)
		(descr "Capacitor SMD 0402")
		(tags "capacitor SMD 0402")
		(property "Reference" "C45"
			(at -3.690905 -0.449013 45)
			(layer "B.SilkS")
			(effects
				(font
					(size 0.7 0.7)
					(thickness 0.15)
				)
				(justify left bottom mirror)
			)
		)
		(property "Value" "C_100n_0402"
			(at -1.022927 -2.155213 45)
			(layer "B.Fab")
			(effects
				(font
					(size 0.7 0.7)
					(thickness 0.15)
				)
				(justify left bottom mirror)
			)
		)
		(property "Datasheet" "https://www.murata.com/products/productdetail?partno=GRM155R61H104KE14%23"
			(at 0 0 225)
			(layer "F.Fab")
			(hide yes)
			(effects
				(font
					(size 1.27 1.27)
					(thickness 0.15)
				)
			)
		)
		(property "Description" "SMD Multilayer Ceramic Capacitor, 0.1 µF, 50 V, 0402 [1005 Metric], ± 10%, X5R, GRM Series"
			(at 0 0 225)
			(layer "F.Fab")
			(hide yes)
			(effects
				(font
					(size 1.27 1.27)
					(thickness 0.15)
				)
			)
		)
		(property "Author" "Antmicro"
			(at 202.16867 239.189005 0)
			(layer "B.Fab")
			(hide yes)
			(effects
				(font
					(size 1 1)
					(thickness 0.15)
				)
				(justify mirror)
			)
		)
		(property "Dielectric" "X5R"
			(at 202.16867 239.189005 0)
			(layer "B.Fab")
			(hide yes)
			(effects
				(font
					(size 1 1)
					(thickness 0.15)
				)
				(justify mirror)
			)
		)
		(property "License" "Apache-2.0"
			(at 202.16867 239.189005 0)
			(layer "B.Fab")
			(hide yes)
			(effects
				(font
					(size 1 1)
					(thickness 0.15)
				)
				(justify mirror)
			)
		)
		(property "MPN" "GRM155R61H104KE14D"
			(at 202.16867 239.189005 0)
			(layer "B.Fab")
			(hide yes)
			(effects
				(font
					(size 1 1)
					(thickness 0.15)
				)
				(justify mirror)
			)
		)
		(property "Manufacturer" "Murata"
			(at 202.16867 239.189005 0)
			(layer "B.Fab")
			(hide yes)
			(effects
				(font
					(size 1 1)
					(thickness 0.15)
				)
				(justify mirror)
			)
		)
		(property "Val" "100n"
			(at 202.16867 239.189005 0)
			(layer "B.Fab")
			(hide yes)
			(effects
				(font
					(size 1 1)
					(thickness 0.15)
				)
				(justify mirror)
			)
		)
		(property "Voltage" "50V"
			(at 202.16867 239.189005 0)
			(layer "B.Fab")
			(hide yes)
			(effects
				(font
					(size 1 1)
					(thickness 0.15)
				)
				(justify mirror)
			)
		)
		(sheetname "/Deserializer/")
		(sheetfile "deserializer.kicad_sch")
		(attr smd)
		(fp_poly
			(pts
				(xy -0.925 0.47) (xy 0.925 0.47) (xy 0.925 -0.47) (xy -0.925 -0.47)
			)
			(stroke
				(width 0.05)
				(type default)
			)
			(fill no)
			(layer "B.CrtYd")
		)
		(fp_line
			(start 0.504 0.25)
			(end -0.494 0.25)
			(stroke
				(width 0.15)
				(type solid)
			)
			(layer "B.Fab")
		)
		(fp_line
			(start 0.504 -0.248)
			(end 0.504 0.25)
			(stroke
				(width 0.15)
				(type solid)
			)
			(layer "B.Fab")
		)
		(fp_line
			(start -0.494 0.25)
			(end -0.494 -0.248)
			(stroke
				(width 0.15)
				(type solid)
			)
			(layer "B.Fab")
		)
		(fp_line
			(start -0.494 -0.248)
			(end 0.504 -0.248)
			(stroke
				(width 0.15)
				(type solid)
			)
			(layer "B.Fab")
		)
		(pad "1" smd roundrect
			(at -0.48 0 225)
			(size 0.59 0.64)
			(layers "B.Cu" "B.Mask" "B.Paste")
			(roundrect_rratio 0.25)
			(net 1 "GND")
			(pintype "passive")
		)
		(pad "2" smd roundrect
			(at 0.48 0 225)
			(size 0.59 0.64)
			(layers "B.Cu" "B.Mask" "B.Paste")
			(roundrect_rratio 0.25)
			(net 26 "/Deserializer/VDD_1.8V")
			(pintype "passive")
		)
	)
)
